# SCM (Grand Teton) — schematic netlist excerpt (pin names and nets, part order shuffled) for the footprints in the layout excerpt that follows; sources: Cadence DE-HDL packaged netlist, KiCad conversion of 12092022_DA0F0TMDCD0_F0T_Management_Board_D_brd_V3_OCP.brd

H7  HOLE  EMPTY  pkg TH  page 57 : \1\ = GND
C305  Q_CAP  1UF 25V 10% X6S  pkg C0402  page 52 : A = PWRGD_P1V8_AUX_R2 ; B = GND
PC263  Q_CAP  0.1UF 25V 10% X7R  pkg 0402  page 56 : A = SW_P1V0_AUX_FLT ; B = GND

(kicad_pcb
	(version 20260206)
	(generator "pcbnew")
	(generator_version "10.0")
	(general
		(thickness 1.6)
		(legacy_teardrops no)
	)
	(paper "A4")
	(title_block
		(title "12092022_DA0F0TMDCD0_F0T_Management_Board_D_brd_V3_OCP.brd")
		(comment 1 "Grand Teton / footprints 286-288 of 1440")
	)
	(layers
		(0 "F.Cu" signal "TOP")
		(4 "In1.Cu" signal "GND")
		(6 "In2.Cu" signal "IN1")
		(8 "In3.Cu" signal "GND1")
		(10 "In4.Cu" signal "IN2")
		(12 "In5.Cu" signal "VCC")
		(14 "In6.Cu" signal "VCC1")
		(16 "In7.Cu" signal "IN3")
		(18 "In8.Cu" signal "GND2")
		(20 "In9.Cu" signal "IN4")
		(22 "In10.Cu" signal "GND3")
		(2 "B.Cu" signal "BOTTOM")
		(9 "F.Adhes" user "F.Adhesive")
		(11 "B.Adhes" user "B.Adhesive")
		(13 "F.Paste" user "Package Geometry/Pastemask Top")
		(15 "B.Paste" user "Package Geometry/Pastemask Bottom")
		(5 "F.SilkS" user "Ref Des/Silkscreen Top")
		(7 "B.SilkS" user "Ref Des/Silkscreen Bottom")
		(1 "F.Mask" user "Board Geometry/Soldermask Top")
		(3 "B.Mask" user "Board Geometry/Soldermask Bottom")
		(17 "Dwgs.User" user "User.Drawings")
		(19 "Cmts.User" user "User.Comments")
		(21 "Eco1.User" user "User.Eco1")
		(23 "Eco2.User" user "User.Eco2")
		(25 "Edge.Cuts" user "Board Geometry/Outline")
		(27 "Margin" user)
		(31 "F.CrtYd" user "Package Geometry/Place Bound Top")
		(29 "B.CrtYd" user "Package Geometry/Place Bound Bottom")
		(35 "F.Fab" user "Ref Des/Assembly Top")
		(33 "B.Fab" user "Ref Des/Assembly Bottom")
	)
	(footprint ""
		(layer "F.Cu")
		(at 19.308826 -34.509964 180)
		(property "Reference" "PC263"
			(at 0 0 180)
			(layer "F.SilkS")
			(hide yes)
			(effects
				(font
					(size 1.27 1.27)
				)
			)
		)
		(property "Value" ""
			(at 0 0 180)
			(layer "F.Fab")
			(effects
				(font
					(size 1.27 1.27)
				)
			)
		)
		(duplicate_pad_numbers_are_jumpers no)
		(fp_line
			(start 0.7874 0.4064)
			(end -0.7874 0.4064)
			(stroke
				(width 0.1524)
				(type default)
			)
			(layer "F.SilkS")
		)
		(fp_line
			(start 0.7874 -0.4064)
			(end 0.7874 0.4064)
			(stroke
				(width 0.1524)
				(type default)
			)
			(layer "F.SilkS")
		)
		(fp_line
			(start -0.7874 0.4064)
			(end -0.7874 -0.4064)
			(stroke
				(width 0.1524)
				(type default)
			)
			(layer "F.SilkS")
		)
		(fp_line
			(start -0.7874 -0.4064)
			(end 0.7874 -0.4064)
			(stroke
				(width 0.1524)
				(type default)
			)
			(layer "F.SilkS")
		)
		(fp_line
			(start 0.67945 0.3048)
			(end 0.120396 0.3048)
			(stroke
				(width 0.1)
				(type default)
			)
			(layer "F.Fab")
		)
		(fp_line
			(start 0.67945 -0.3048)
			(end 0.67945 0.3048)
			(stroke
				(width 0.1)
				(type default)
			)
			(layer "F.Fab")
		)
		(fp_line
			(start 0.12065 -0.2794)
			(end 0.12065 -0.3048)
			(stroke
				(width 0.1)
				(type default)
			)
			(layer "F.Fab")
		)
		(fp_line
			(start 0.12065 -0.3048)
			(end 0.67945 -0.3048)
			(stroke
				(width 0.1)
				(type default)
			)
			(layer "F.Fab")
		)
		(fp_line
			(start 0.120396 0.3048)
			(end 0.120396 0.2794)
			(stroke
				(width 0.1)
				(type default)
			)
			(layer "F.Fab")
		)
		(fp_line
			(start 0.120396 0.2794)
			(end -0.12065 0.2794)
			(stroke
				(width 0.1)
				(type default)
			)
			(layer "F.Fab")
		)
		(fp_line
			(start -0.12065 0.3048)
			(end -0.67945 0.3048)
			(stroke
				(width 0.1)
				(type default)
			)
			(layer "F.Fab")
		)
		(fp_line
			(start -0.12065 0.2794)
			(end -0.12065 0.3048)
			(stroke
				(width 0.1)
				(type default)
			)
			(layer "F.Fab")
		)
		(fp_line
			(start -0.12065 -0.2794)
			(end 0.12065 -0.2794)
			(stroke
				(width 0.1)
				(type default)
			)
			(layer "F.Fab")
		)
		(fp_line
			(start -0.12065 -0.305054)
			(end -0.12065 -0.2794)
			(stroke
				(width 0.1)
				(type default)
			)
			(layer "F.Fab")
		)
		(fp_line
			(start -0.67945 0.3048)
			(end -0.67945 -0.305054)
			(stroke
				(width 0.1)
				(type default)
			)
			(layer "F.Fab")
		)
		(fp_line
			(start -0.67945 -0.305054)
			(end -0.12065 -0.305054)
			(stroke
				(width 0.1)
				(type default)
			)
			(layer "F.Fab")
		)
		(pad "1" smd circle
			(at -0.40005 0 180)
			(size 0 0)
			(layers "F.Cu" "F.Mask" "F.Paste")
			(net "SW_P1V0_AUX_FLT")
		)
		(pad "2" smd circle
			(at 0.40005 0 180)
			(size 0 0)
			(layers "F.Cu" "F.Mask" "F.Paste")
			(net "GND")
		)
	)
	(footprint ""
		(layer "F.Cu")
		(at 84.700364 -11.789918)
		(property "Reference" "H7"
			(at -4.842764 -2.280412 0)
			(unlocked yes)
			(layer "F.SilkS")
			(effects
				(font
					(size 0.7874 0.5842)
					(thickness 0.1524)
				)
				(justify left)
			)
		)
		(property "Value" ""
			(at 0 0 0)
			(layer "F.Fab")
			(effects
				(font
					(size 1.27 1.27)
				)
			)
		)
		(duplicate_pad_numbers_are_jumpers no)
		(pad "1" thru_hole circle
			(at 0 0)
			(size 6.5024 6.5024)
			(drill 3.2004)
			(layers "*.Cu" "*.Mask")
			(remove_unused_layers no)
			(net "GND")
			(clearance -1.397)
		)
	)
	(footprint ""
		(layer "F.Cu")
		(at 13.5001 -53.6448 180)
		(property "Reference" "C305"
			(at 0 0 180)
			(layer "F.SilkS")
			(hide yes)
			(effects
				(font
					(size 1.27 1.27)
				)
			)
		)
		(property "Value" ""
			(at 0 0 180)
			(layer "F.Fab")
			(effects
				(font
					(size 1.27 1.27)
				)
			)
		)
		(duplicate_pad_numbers_are_jumpers no)
		(fp_line
			(start 0.7874 0.4064)
			(end -0.7874 0.4064)
			(stroke
				(width 0.1524)
				(type default)
			)
			(layer "F.SilkS")
		)
		(fp_line
			(start 0.7874 -0.4064)
			(end 0.7874 0.4064)
			(stroke
				(width 0.1524)
				(type default)
			)
			(layer "F.SilkS")
		)
		(fp_line
			(start -0.7874 0.4064)
			(end -0.7874 -0.4064)
			(stroke
				(width 0.1524)
				(type default)
			)
			(layer "F.SilkS")
		)
		(fp_line
			(start -0.7874 -0.4064)
			(end 0.7874 -0.4064)
			(stroke
				(width 0.1524)
				(type default)
			)
			(layer "F.SilkS")
		)
		(fp_line
			(start 0.67945 0.3048)
			(end 0.120396 0.3048)
			(stroke
				(width 0.1)
				(type default)
			)
			(layer "F.Fab")
		)
		(fp_line
			(start 0.67945 -0.3048)
			(end 0.67945 0.3048)
			(stroke
				(width 0.1)
				(type default)
			)
			(layer "F.Fab")
		)
		(fp_line
			(start 0.12065 -0.2794)
			(end 0.12065 -0.3048)
			(stroke
				(width 0.1)
				(type default)
			)
			(layer "F.Fab")
		)
		(fp_line
			(start 0.12065 -0.3048)
			(end 0.67945 -0.3048)
			(stroke
				(width 0.1)
				(type default)
			)
			(layer "F.Fab")
		)
		(fp_line
			(start 0.120396 0.3048)
			(end 0.120396 0.2794)
			(stroke
				(width 0.1)
				(type default)
			)
			(layer "F.Fab")
		)
		(fp_line
			(start 0.120396 0.2794)
			(end -0.12065 0.2794)
			(stroke
				(width 0.1)
				(type default)
			)
			(layer "F.Fab")
		)
		(fp_line
			(start -0.12065 0.3048)
			(end -0.67945 0.3048)
			(stroke
				(width 0.1)
				(type default)
			)
			(layer "F.Fab")
		)
		(fp_line
			(start -0.12065 0.2794)
			(end -0.12065 0.3048)
			(stroke
				(width 0.1)
				(type default)
			)
			(layer "F.Fab")
		)
		(fp_line
			(start -0.12065 -0.2794)
			(end 0.12065 -0.2794)
			(stroke
				(width 0.1)
				(type default)
			)
			(layer "F.Fab")
		)
		(fp_line
			(start -0.12065 -0.305054)
			(end -0.12065 -0.2794)
			(stroke
				(width 0.1)
				(type default)
			)
			(layer "F.Fab")
		)
		(fp_line
			(start -0.67945 0.3048)
			(end -0.67945 -0.305054)
			(stroke
				(width 0.1)
				(type default)
			)
			(layer "F.Fab")
		)
		(fp_line
			(start -0.67945 -0.305054)
			(end -0.12065 -0.305054)
			(stroke
				(width 0.1)
				(type default)
			)
			(layer "F.Fab")
		)
		(pad "1" smd circle
			(at -0.40005 0 180)
			(size 0 0)
			(layers "F.Cu" "F.Mask" "F.Paste")
			(net "PWRGD_P1V8_AUX_R2")
		)
		(pad "2" smd circle
			(at 0.40005 0 180)
			(size 0 0)
			(layers "F.Cu" "F.Mask" "F.Paste")
			(net "GND")
		)
	)
)
